# S9S_MB_2U (Grand Teton) — schematic netlist excerpt (pin names and nets, part order shuffled) for the footprints in the layout excerpt that follows; sources: Cadence DE-HDL packaged netlist, KiCad conversion of 03242023_DA0F0TMBIJ0_F0T_Motherboard_J_brd_V01_OCP.brd

R2999  Q_RES  2.2K 5% EMPTY  pkg 0402LF  page 241 : A = SMB_2_BMC_GPU_SCL ; B = P3V3_AUX
R3680  Q_RES  0 5% CHIP  pkg 0402LF  page 250 : A = P12V_AUX_ADC ; B = P12V_AUX_ADC_TIC

(kicad_pcb
	(version 20260206)
	(generator "pcbnew")
	(generator_version "10.0")
	(general
		(thickness 1.6)
		(legacy_teardrops no)
	)
	(paper "A4")
	(title_block
		(title "03242023_DA0F0TMBIJ0_F0T_Motherboard_J_brd_V01_OCP.brd")
		(comment 1 "Grand Teton / footprints 122-123 of 6105")
	)
	(layers
		(0 "F.Cu" signal "TOP")
		(4 "In1.Cu" signal "GND")
		(6 "In2.Cu" signal "IN1")
		(8 "In3.Cu" signal "GND1")
		(10 "In4.Cu" signal "IN2")
		(12 "In5.Cu" signal "GND2")
		(14 "In6.Cu" signal "IN3")
		(16 "In7.Cu" signal "GND3")
		(18 "In8.Cu" signal "VCC")
		(20 "In9.Cu" signal "VCC1")
		(22 "In10.Cu" signal "GND4")
		(24 "In11.Cu" signal "IN4")
		(26 "In12.Cu" signal "GND5")
		(28 "In13.Cu" signal "IN5")
		(30 "In14.Cu" signal "GND6")
		(32 "In15.Cu" signal "IN6")
		(34 "In16.Cu" signal "GND7")
		(2 "B.Cu" signal "BOTTOM")
		(9 "F.Adhes" user "F.Adhesive")
		(11 "B.Adhes" user "B.Adhesive")
		(13 "F.Paste" user "Package Geometry/Pastemask Top")
		(15 "B.Paste" user "Package Geometry/Pastemask Bottom")
		(5 "F.SilkS" user "Ref Des/Silkscreen Top")
		(7 "B.SilkS" user "Ref Des/Silkscreen Bottom")
		(1 "F.Mask" user "Board Geometry/Soldermask Top")
		(3 "B.Mask" user "Board Geometry/Soldermask Bottom")
		(17 "Dwgs.User" user "User.Drawings")
		(19 "Cmts.User" user "User.Comments")
		(21 "Eco1.User" user "User.Eco1")
		(23 "Eco2.User" user "User.Eco2")
		(25 "Edge.Cuts" user "Board Geometry/Outline")
		(27 "Margin" user)
		(31 "F.CrtYd" user "Package Geometry/Place Bound Top")
		(29 "B.CrtYd" user "Package Geometry/Place Bound Bottom")
		(35 "F.Fab" user "Ref Des/Assembly Top")
		(33 "B.Fab" user "Ref Des/Assembly Bottom")
	)
	(footprint ""
		(layer "F.Cu")
		(at 39.827454 -112.603026 180)
		(property "Reference" "R3680"
			(at 0 0 180)
			(layer "F.SilkS")
			(hide yes)
			(effects
				(font
					(size 1.27 1.27)
				)
			)
		)
		(property "Value" ""
			(at 0 0 180)
			(layer "F.Fab")
			(effects
				(font
					(size 1.27 1.27)
				)
			)
		)
		(duplicate_pad_numbers_are_jumpers no)
		(fp_line
			(start 0.7874 0.4064)
			(end -0.7874 0.4064)
			(stroke
				(width 0.1524)
				(type default)
			)
			(layer "F.SilkS")
		)
		(fp_line
			(start 0.7874 -0.4064)
			(end 0.7874 0.4064)
			(stroke
				(width 0.1524)
				(type default)
			)
			(layer "F.SilkS")
		)
		(fp_line
			(start -0.7874 0.4064)
			(end -0.7874 -0.4064)
			(stroke
				(width 0.1524)
				(type default)
			)
			(layer "F.SilkS")
		)
		(fp_line
			(start -0.7874 -0.4064)
			(end 0.7874 -0.4064)
			(stroke
				(width 0.1524)
				(type default)
			)
			(layer "F.SilkS")
		)
		(fp_line
			(start 0.67945 0.3048)
			(end 0.120396 0.3048)
			(stroke
				(width 0.1)
				(type default)
			)
			(layer "F.Fab")
		)
		(fp_line
			(start 0.67945 -0.3048)
			(end 0.67945 0.3048)
			(stroke
				(width 0.1)
				(type default)
			)
			(layer "F.Fab")
		)
		(fp_line
			(start 0.12065 -0.2794)
			(end 0.12065 -0.3048)
			(stroke
				(width 0.1)
				(type default)
			)
			(layer "F.Fab")
		)
		(fp_line
			(start 0.12065 -0.3048)
			(end 0.67945 -0.3048)
			(stroke
				(width 0.1)
				(type default)
			)
			(layer "F.Fab")
		)
		(fp_line
			(start 0.120396 0.3048)
			(end 0.120396 0.2794)
			(stroke
				(width 0.1)
				(type default)
			)
			(layer "F.Fab")
		)
		(fp_line
			(start 0.120396 0.2794)
			(end -0.12065 0.2794)
			(stroke
				(width 0.1)
				(type default)
			)
			(layer "F.Fab")
		)
		(fp_line
			(start -0.12065 0.3048)
			(end -0.67945 0.3048)
			(stroke
				(width 0.1)
				(type default)
			)
			(layer "F.Fab")
		)
		(fp_line
			(start -0.12065 0.2794)
			(end -0.12065 0.3048)
			(stroke
				(width 0.1)
				(type default)
			)
			(layer "F.Fab")
		)
		(fp_line
			(start -0.12065 -0.2794)
			(end 0.12065 -0.2794)
			(stroke
				(width 0.1)
				(type default)
			)
			(layer "F.Fab")
		)
		(fp_line
			(start -0.12065 -0.305054)
			(end -0.12065 -0.2794)
			(stroke
				(width 0.1)
				(type default)
			)
			(layer "F.Fab")
		)
		(fp_line
			(start -0.67945 0.3048)
			(end -0.67945 -0.305054)
			(stroke
				(width 0.1)
				(type default)
			)
			(layer "F.Fab")
		)
		(fp_line
			(start -0.67945 -0.305054)
			(end -0.12065 -0.305054)
			(stroke
				(width 0.1)
				(type default)
			)
			(layer "F.Fab")
		)
		(pad "1" smd rect
			(at -0.40005 0)
			(size 0.4572 0.508)
			(layers "F.Cu" "F.Mask" "F.Paste")
			(net "P12V_AUX_ADC")
		)
		(pad "2" smd rect
			(at 0.40005 0)
			(size 0.4572 0.508)
			(layers "F.Cu" "F.Mask" "F.Paste")
			(net "P12V_AUX_ADC_TIC")
		)
	)
	(footprint ""
		(layer "F.Cu")
		(at 50.95875 -440.187588)
		(property "Reference" "R2999"
			(at 0 0 0)
			(layer "F.SilkS")
			(hide yes)
			(effects
				(font
					(size 1.27 1.27)
				)
			)
		)
		(property "Value" ""
			(at 0 0 0)
			(layer "F.Fab")
			(effects
				(font
					(size 1.27 1.27)
				)
			)
		)
		(duplicate_pad_numbers_are_jumpers no)
		(fp_line
			(start -0.7874 -0.4064)
			(end 0.7874 -0.4064)
			(stroke
				(width 0.1524)
				(type default)
			)
			(layer "F.SilkS")
		)
		(fp_line
			(start -0.7874 0.4064)
			(end -0.7874 -0.4064)
			(stroke
				(width 0.1524)
				(type default)
			)
			(layer "F.SilkS")
		)
		(fp_line
			(start 0.7874 -0.4064)
			(end 0.7874 0.4064)
			(stroke
				(width 0.1524)
				(type default)
			)
			(layer "F.SilkS")
		)
		(fp_line
			(start 0.7874 0.4064)
			(end -0.7874 0.4064)
			(stroke
				(width 0.1524)
				(type default)
			)
			(layer "F.SilkS")
		)
		(fp_line
			(start -0.67945 -0.305054)
			(end -0.12065 -0.305054)
			(stroke
				(width 0.1)
				(type default)
			)
			(layer "F.Fab")
		)
		(fp_line
			(start -0.67945 0.3048)
			(end -0.67945 -0.305054)
			(stroke
				(width 0.1)
				(type default)
			)
			(layer "F.Fab")
		)
		(fp_line
			(start -0.12065 -0.305054)
			(end -0.12065 -0.2794)
			(stroke
				(width 0.1)
				(type default)
			)
			(layer "F.Fab")
		)
		(fp_line
			(start -0.12065 -0.2794)
			(end 0.12065 -0.2794)
			(stroke
				(width 0.1)
				(type default)
			)
			(layer "F.Fab")
		)
		(fp_line
			(start -0.12065 0.2794)
			(end -0.12065 0.3048)
			(stroke
				(width 0.1)
				(type default)
			)
			(layer "F.Fab")
		)
		(fp_line
			(start -0.12065 0.3048)
			(end -0.67945 0.3048)
			(stroke
				(width 0.1)
				(type default)
			)
			(layer "F.Fab")
		)
		(fp_line
			(start 0.120396 0.2794)
			(end -0.12065 0.2794)
			(stroke
				(width 0.1)
				(type default)
			)
			(layer "F.Fab")
		)
		(fp_line
			(start 0.120396 0.3048)
			(end 0.120396 0.2794)
			(stroke
				(width 0.1)
				(type default)
			)
			(layer "F.Fab")
		)
		(fp_line
			(start 0.12065 -0.3048)
			(end 0.67945 -0.3048)
			(stroke
				(width 0.1)
				(type default)
			)
			(layer "F.Fab")
		)
		(fp_line
			(start 0.12065 -0.2794)
			(end 0.12065 -0.3048)
			(stroke
				(width 0.1)
				(type default)
			)
			(layer "F.Fab")
		)
		(fp_line
			(start 0.67945 -0.3048)
			(end 0.67945 0.3048)
			(stroke
				(width 0.1)
				(type default)
			)
			(layer "F.Fab")
		)
		(fp_line
			(start 0.67945 0.3048)
			(end 0.120396 0.3048)
			(stroke
				(width 0.1)
				(type default)
			)
			(layer "F.Fab")
		)
		(pad "1" smd circle
			(at -0.40005 0)
			(size 0 0)
			(layers "F.Cu" "F.Mask" "F.Paste")
			(net "SMB_2_BMC_GPU_SCL")
		)
		(pad "2" smd circle
			(at 0.40005 0)
			(size 0 0)
			(layers "F.Cu" "F.Mask" "F.Paste")
			(net "P3V3_AUX")
		)
	)
)
